(kicad_pcb
	(version 20260206)
	(generator "pcbnew")
	(generator_version "10.0")
	(general
		(thickness 1.6)
		(legacy_teardrops no)
	)
	(paper "A4")
	(title_block
		(title "03242023_DA0F0TMBIJ0_F0T_Motherboard_J_brd_V01_OCP.brd")
		(comment 1 "Grand Teton / footprint 3039 of 6105 (U2), pads 3024-3133 of 4677")
	)
	(layers
		(0 "F.Cu" signal "TOP")
		(4 "In1.Cu" signal "GND")
		(6 "In2.Cu" signal "IN1")
		(8 "In3.Cu" signal "GND1")
		(10 "In4.Cu" signal "IN2")
		(12 "In5.Cu" signal "GND2")
		(14 "In6.Cu" signal "IN3")
		(16 "In7.Cu" signal "GND3")
		(18 "In8.Cu" signal "VCC")
		(20 "In9.Cu" signal "VCC1")
		(22 "In10.Cu" signal "GND4")
		(24 "In11.Cu" signal "IN4")
		(26 "In12.Cu" signal "GND5")
		(28 "In13.Cu" signal "IN5")
		(30 "In14.Cu" signal "GND6")
		(32 "In15.Cu" signal "IN6")
		(34 "In16.Cu" signal "GND7")
		(2 "B.Cu" signal "BOTTOM")
		(9 "F.Adhes" user "F.Adhesive")
		(11 "B.Adhes" user "B.Adhesive")
		(13 "F.Paste" user "Package Geometry/Pastemask Top")
		(15 "B.Paste" user "Package Geometry/Pastemask Bottom")
		(5 "F.SilkS" user "Ref Des/Silkscreen Top")
		(7 "B.SilkS" user "Ref Des/Silkscreen Bottom")
		(1 "F.Mask" user "Board Geometry/Soldermask Top")
		(3 "B.Mask" user "Board Geometry/Soldermask Bottom")
		(17 "Dwgs.User" user "User.Drawings")
		(19 "Cmts.User" user "User.Comments")
		(21 "Eco1.User" user "User.Eco1")
		(23 "Eco2.User" user "User.Eco2")
		(25 "Edge.Cuts" user "Board Geometry/Outline")
		(27 "Margin" user)
		(31 "F.CrtYd" user "Package Geometry/Place Bound Top")
		(29 "B.CrtYd" user "Package Geometry/Place Bound Bottom")
		(35 "F.Fab" user "Ref Des/Assembly Top")
		(33 "B.Fab" user "Ref Des/Assembly Bottom")
	)
	(footprint ""
		(layer "F.Cu")
		(at 359.870248 -251.76988 90)
		(property "Reference" "U2"
			(at -74.416158 -44.488608 0)
			(unlocked yes)
			(layer "F.SilkS")
			(effects
				(font
					(size 1.6002 1.1938)
					(thickness 0.1524)
				)
				(justify left)
			)
		)
		(property "Value" ""
			(at 0 0 90)
			(layer "F.Fab")
			(effects
				(font
					(size 1.27 1.27)
				)
			)
		)
		(duplicate_pad_numbers_are_jumpers no)
		(pad "DR7" smd circle
			(at -32.541718 17.096486 270)
			(size 0.4318 0.4318)
			(layers "F.Cu" "F.Mask" "F.Paste")
			(net "UPI_CPU0_CPU1_P1P0_DN<5>")
		)
		(pad "DR9" smd circle
			(at -30.914086 17.096486 270)
			(size 0.4318 0.4318)
			(layers "F.Cu" "F.Mask" "F.Paste")
			(net "GND")
		)
		(pad "DR11" smd circle
			(at -29.2862 17.096486 270)
			(size 0.4318 0.4318)
			(layers "F.Cu" "F.Mask" "F.Paste")
			(net "P5E_CPU0_PE2_RX_DP<9>")
		)
		(pad "DR13" smd circle
			(at -27.658314 17.096486 270)
			(size 0.4318 0.4318)
			(layers "F.Cu" "F.Mask" "F.Paste")
			(net "GND")
		)
		(pad "DR15" smd circle
			(at -26.030682 17.096486 270)
			(size 0.4318 0.4318)
			(layers "F.Cu" "F.Mask" "F.Paste")
			(net "P5E_CPU0_PE2_TX_DP<9>")
		)
		(pad "DR17" smd circle
			(at -24.402796 17.096486 270)
			(size 0.4318 0.4318)
			(layers "F.Cu" "F.Mask" "F.Paste")
			(net "M_F_CPU0_SB_DQ<31>")
		)
		(pad "DR19" smd circle
			(at -22.77491 17.096486 270)
			(size 0.4318 0.4318)
			(layers "F.Cu" "F.Mask" "F.Paste")
			(net "GND")
		)
		(pad "DR21" smd circle
			(at -21.147278 17.096486 270)
			(size 0.4318 0.4318)
			(layers "F.Cu" "F.Mask" "F.Paste")
			(net "M_H_CPU0_SB_DQS_DN<7>")
		)
		(pad "DR23" smd circle
			(at -19.519392 17.096486 270)
			(size 0.4318 0.4318)
			(layers "F.Cu" "F.Mask" "F.Paste")
			(net "GND")
		)
		(pad "DR25" smd circle
			(at -17.89176 17.096486 270)
			(size 0.4318 0.4318)
			(layers "F.Cu" "F.Mask" "F.Paste")
			(net "GND")
		)
		(pad "DR27" smd circle
			(at -16.263874 17.096486 270)
			(size 0.4318 0.4318)
			(layers "F.Cu" "F.Mask" "F.Paste")
			(net "M_G_CPU0_SB_DQS_DP<6>")
		)
		(pad "DR29" smd circle
			(at -14.635988 17.096486 270)
			(size 0.4318 0.4318)
			(layers "F.Cu" "F.Mask" "F.Paste")
			(net "GND")
		)
		(pad "DR31" smd circle
			(at -13.008356 17.096486 270)
			(size 0.4318 0.4318)
			(layers "F.Cu" "F.Mask" "F.Paste")
			(net "GND")
		)
		(pad "DR33" smd circle
			(at -11.380724 17.096486 270)
			(size 0.4318 0.4318)
			(layers "F.Cu" "F.Mask" "F.Paste")
			(net "M_G_CPU0_SB_DQS_DN<5>")
		)
		(pad "DR35" smd circle
			(at -9.752838 17.096486 270)
			(size 0.4318 0.4318)
			(layers "F.Cu" "F.Mask" "F.Paste")
			(net "GND")
		)
		(pad "DR37" smd circle
			(at -8.124952 17.096486 270)
			(size 0.4318 0.4318)
			(layers "F.Cu" "F.Mask" "F.Paste")
			(net "GND")
		)
		(pad "DR39" smd circle
			(at -6.49732 17.096486 270)
			(size 0.4318 0.4318)
			(layers "F.Cu" "F.Mask" "F.Paste")
			(net "M_H_CPU0_SB_PAR")
		)
		(pad "DR41" smd circle
			(at -4.869434 17.096486 270)
			(size 0.4318 0.4318)
			(layers "F.Cu" "F.Mask" "F.Paste")
			(net "GND")
		)
		(pad "DR43" smd circle
			(at -3.241802 17.096486 270)
			(size 0.4318 0.4318)
			(layers "F.Cu" "F.Mask" "F.Paste")
			(net "GND")
		)
		(pad "DR45" smd circle
			(at -1.613916 17.096486 270)
			(size 0.4318 0.4318)
			(layers "F.Cu" "F.Mask" "F.Paste")
			(net "M_G_CPU0_CLK_DN<0>")
		)
		(pad "DR48" smd circle
			(at 2.427732 17.206468 270)
			(size 0.4318 0.4318)
			(layers "F.Cu" "F.Mask" "F.Paste")
			(net "GND")
		)
		(pad "DR50" smd circle
			(at 4.055618 17.206468 270)
			(size 0.4318 0.4318)
			(layers "F.Cu" "F.Mask" "F.Paste")
			(net "GND")
		)
		(pad "DR52" smd circle
			(at 5.68325 17.206468 270)
			(size 0.4318 0.4318)
			(layers "F.Cu" "F.Mask" "F.Paste")
			(net "M_G_CPU0_SA_CA<1>")
		)
		(pad "DR54" smd circle
			(at 7.311136 17.206468 270)
			(size 0.4318 0.4318)
			(layers "F.Cu" "F.Mask" "F.Paste")
			(net "GND")
		)
		(pad "DR56" smd circle
			(at 8.939022 17.206468 270)
			(size 0.4318 0.4318)
			(layers "F.Cu" "F.Mask" "F.Paste")
			(net "GND")
		)
		(pad "DR58" smd circle
			(at 10.566654 17.206468 270)
			(size 0.4318 0.4318)
			(layers "F.Cu" "F.Mask" "F.Paste")
			(net "M_G_CPU0_SA_DQS_DN<9>")
		)
		(pad "DR60" smd circle
			(at 12.19454 17.206468 270)
			(size 0.4318 0.4318)
			(layers "F.Cu" "F.Mask" "F.Paste")
			(net "GND")
		)
		(pad "DR62" smd circle
			(at 13.822426 17.206468 270)
			(size 0.4318 0.4318)
			(layers "F.Cu" "F.Mask" "F.Paste")
			(net "GND")
		)
		(pad "DR64" smd circle
			(at 15.450058 17.206468 270)
			(size 0.4318 0.4318)
			(layers "F.Cu" "F.Mask" "F.Paste")
			(net "M_G_CPU0_SA_DQS_DN<8>")
		)
		(pad "DR66" smd circle
			(at 17.07769 17.206468 270)
			(size 0.4318 0.4318)
			(layers "F.Cu" "F.Mask" "F.Paste")
			(net "GND")
		)
		(pad "DR68" smd circle
			(at 18.705576 17.206468 270)
			(size 0.4318 0.4318)
			(layers "F.Cu" "F.Mask" "F.Paste")
			(net "GND")
		)
		(pad "DR70" smd circle
			(at 20.333462 17.206468 270)
			(size 0.4318 0.4318)
			(layers "F.Cu" "F.Mask" "F.Paste")
			(net "M_G_CPU0_SA_DQS_DN<6>")
		)
		(pad "DR72" smd circle
			(at 21.961094 17.206468 270)
			(size 0.4318 0.4318)
			(layers "F.Cu" "F.Mask" "F.Paste")
			(net "GND")
		)
		(pad "DR74" smd circle
			(at 23.58898 17.206468 270)
			(size 0.4318 0.4318)
			(layers "F.Cu" "F.Mask" "F.Paste")
			(net "GND")
		)
		(pad "DR76" smd circle
			(at 25.216612 17.206468 270)
			(size 0.4318 0.4318)
			(layers "F.Cu" "F.Mask" "F.Paste")
			(net "M_H_CPU0_SA_DQS_DN<5>")
		)
		(pad "DR78" smd circle
			(at 26.844498 17.206468 270)
			(size 0.4318 0.4318)
			(layers "F.Cu" "F.Mask" "F.Paste")
			(net "GND")
		)
		(pad "DR80" smd circle
			(at 28.472384 17.206468 270)
			(size 0.4318 0.4318)
			(layers "F.Cu" "F.Mask" "F.Paste")
			(net "Net_655")
		)
		(pad "DR82" smd circle
			(at 30.100016 17.206468 270)
			(size 0.4318 0.4318)
			(layers "F.Cu" "F.Mask" "F.Paste")
			(net "Net_680")
		)
		(pad "DR84" smd circle
			(at 31.727902 17.206468 270)
			(size 0.4318 0.4318)
			(layers "F.Cu" "F.Mask" "F.Paste")
			(net "GND")
		)
		(pad "DR86" smd circle
			(at 33.355534 17.206468 270)
			(size 0.4318 0.4318)
			(layers "F.Cu" "F.Mask" "F.Paste")
			(net "P5E_CPU0_PE3_TX_DP<5>")
		)
		(pad "DR88" smd circle
			(at 34.98342 17.206468 270)
			(size 0.4318 0.4318)
			(layers "F.Cu" "F.Mask" "F.Paste")
			(net "GND")
		)
		(pad "DR90" smd circle
			(at 36.611306 17.206468 270)
			(size 0.4318 0.4318)
			(layers "F.Cu" "F.Mask" "F.Paste")
			(net "P5E_CPU0_PE3_RX_DP<6>")
		)
		(pad "DT2" smd circle
			(at -36.611306 17.566132 270)
			(size 0.4318 0.4318)
			(layers "F.Cu" "F.Mask" "F.Paste")
			(net "UPI_CPU1_CPU0_P0P1_DN<6>")
		)
		(pad "DT4" smd circle
			(at -34.98342 17.566132 270)
			(size 0.4318 0.4318)
			(layers "F.Cu" "F.Mask" "F.Paste")
			(net "GND")
		)
		(pad "DT6" smd circle
			(at -33.355534 17.566132 270)
			(size 0.4318 0.4318)
			(layers "F.Cu" "F.Mask" "F.Paste")
			(net "UPI_CPU0_CPU1_P1P0_DP<5>")
		)
		(pad "DT8" smd circle
			(at -31.727902 17.566132 270)
			(size 0.4318 0.4318)
			(layers "F.Cu" "F.Mask" "F.Paste")
			(net "GND")
		)
		(pad "DT10" smd circle
			(at -30.100016 17.566132 270)
			(size 0.4318 0.4318)
			(layers "F.Cu" "F.Mask" "F.Paste")
			(net "P5E_CPU0_PE2_RX_DN<9>")
		)
		(pad "DT12" smd circle
			(at -28.472384 17.566132 270)
			(size 0.4318 0.4318)
			(layers "F.Cu" "F.Mask" "F.Paste")
			(net "GND")
		)
		(pad "DT14" smd circle
			(at -26.844498 17.566132 270)
			(size 0.4318 0.4318)
			(layers "F.Cu" "F.Mask" "F.Paste")
			(net "P5E_CPU0_PE2_TX_DP<10>")
		)
		(pad "DT16" smd circle
			(at -25.216612 17.566132 270)
			(size 0.4318 0.4318)
			(layers "F.Cu" "F.Mask" "F.Paste")
			(net "GND")
		)
		(pad "DT18" smd circle
			(at -23.58898 17.566132 270)
			(size 0.4318 0.4318)
			(layers "F.Cu" "F.Mask" "F.Paste")
			(net "M_F_CPU0_SB_DQS_DN<3>")
		)
		(pad "DT20" smd circle
			(at -21.961094 17.566132 270)
			(size 0.4318 0.4318)
			(layers "F.Cu" "F.Mask" "F.Paste")
			(net "GND")
		)
		(pad "DT22" smd circle
			(at -20.333462 17.566132 270)
			(size 0.4318 0.4318)
			(layers "F.Cu" "F.Mask" "F.Paste")
			(net "GND")
		)
		(pad "DT24" smd circle
			(at -18.705576 17.566132 270)
			(size 0.4318 0.4318)
			(layers "F.Cu" "F.Mask" "F.Paste")
			(net "M_G_CPU0_SB_DQS_DP<2>")
		)
		(pad "DT26" smd circle
			(at -17.07769 17.566132 270)
			(size 0.4318 0.4318)
			(layers "F.Cu" "F.Mask" "F.Paste")
			(net "GND")
		)
		(pad "DT28" smd circle
			(at -15.450058 17.566132 270)
			(size 0.4318 0.4318)
			(layers "F.Cu" "F.Mask" "F.Paste")
			(net "GND")
		)
		(pad "DT30" smd circle
			(at -13.822426 17.566132 270)
			(size 0.4318 0.4318)
			(layers "F.Cu" "F.Mask" "F.Paste")
			(net "M_F_CPU0_SB_DQS_DP<0>")
		)
		(pad "DT32" smd circle
			(at -12.19454 17.566132 270)
			(size 0.4318 0.4318)
			(layers "F.Cu" "F.Mask" "F.Paste")
			(net "GND")
		)
		(pad "DT34" smd circle
			(at -10.566654 17.566132 270)
			(size 0.4318 0.4318)
			(layers "F.Cu" "F.Mask" "F.Paste")
			(net "GND")
		)
		(pad "DT36" smd circle
			(at -8.939022 17.566132 270)
			(size 0.4318 0.4318)
			(layers "F.Cu" "F.Mask" "F.Paste")
			(net "M_G_CPU0_SB_DQS_DP<9>")
		)
		(pad "DT38" smd circle
			(at -7.311136 17.566132 270)
			(size 0.4318 0.4318)
			(layers "F.Cu" "F.Mask" "F.Paste")
			(net "GND")
		)
		(pad "DT40" smd circle
			(at -5.68325 17.566132 270)
			(size 0.4318 0.4318)
			(layers "F.Cu" "F.Mask" "F.Paste")
			(net "GND")
		)
		(pad "DT42" smd circle
			(at -4.055618 17.566132 270)
			(size 0.4318 0.4318)
			(layers "F.Cu" "F.Mask" "F.Paste")
			(net "M_G_CPU0_SB_CA<6>")
		)
		(pad "DT44" smd circle
			(at -2.427732 17.566132 270)
			(size 0.4318 0.4318)
			(layers "F.Cu" "F.Mask" "F.Paste")
			(net "GND")
		)
		(pad "DT47" smd circle
			(at 1.613916 17.676114 270)
			(size 0.4318 0.4318)
			(layers "F.Cu" "F.Mask" "F.Paste")
			(net "GND")
		)
		(pad "DT49" smd circle
			(at 3.241802 17.676114 270)
			(size 0.4318 0.4318)
			(layers "F.Cu" "F.Mask" "F.Paste")
			(net "M_F_CPU0_CLK_DP<1>")
		)
		(pad "DT51" smd circle
			(at 4.869434 17.676114 270)
			(size 0.4318 0.4318)
			(layers "F.Cu" "F.Mask" "F.Paste")
			(net "GND")
		)
		(pad "DT53" smd circle
			(at 6.49732 17.676114 270)
			(size 0.4318 0.4318)
			(layers "F.Cu" "F.Mask" "F.Paste")
			(net "GND")
		)
		(pad "DT55" smd circle
			(at 8.124952 17.676114 270)
			(size 0.4318 0.4318)
			(layers "F.Cu" "F.Mask" "F.Paste")
			(net "M_F_CPU0_SA_DQS_DP<3>")
		)
		(pad "DT57" smd circle
			(at 9.752838 17.676114 270)
			(size 0.4318 0.4318)
			(layers "F.Cu" "F.Mask" "F.Paste")
			(net "GND")
		)
		(pad "DT59" smd circle
			(at 11.380724 17.676114 270)
			(size 0.4318 0.4318)
			(layers "F.Cu" "F.Mask" "F.Paste")
			(net "GND")
		)
		(pad "DT61" smd circle
			(at 13.008356 17.676114 270)
			(size 0.4318 0.4318)
			(layers "F.Cu" "F.Mask" "F.Paste")
			(net "M_G_CPU0_SA_DQS_DN<2>")
		)
		(pad "DT63" smd circle
			(at 14.635988 17.676114 270)
			(size 0.4318 0.4318)
			(layers "F.Cu" "F.Mask" "F.Paste")
			(net "GND")
		)
		(pad "DT65" smd circle
			(at 16.263874 17.676114 270)
			(size 0.4318 0.4318)
			(layers "F.Cu" "F.Mask" "F.Paste")
			(net "GND")
		)
		(pad "DT67" smd circle
			(at 17.89176 17.676114 270)
			(size 0.4318 0.4318)
			(layers "F.Cu" "F.Mask" "F.Paste")
			(net "M_F_CPU0_SA_DQS_DN<1>")
		)
		(pad "DT69" smd circle
			(at 19.519392 17.676114 270)
			(size 0.4318 0.4318)
			(layers "F.Cu" "F.Mask" "F.Paste")
			(net "GND")
		)
		(pad "DT71" smd circle
			(at 21.147278 17.676114 270)
			(size 0.4318 0.4318)
			(layers "F.Cu" "F.Mask" "F.Paste")
			(net "GND")
		)
		(pad "DT73" smd circle
			(at 22.77491 17.676114 270)
			(size 0.4318 0.4318)
			(layers "F.Cu" "F.Mask" "F.Paste")
			(net "M_G_CPU0_SA_DQS_DP<0>")
		)
		(pad "DT75" smd circle
			(at 24.402796 17.676114 270)
			(size 0.4318 0.4318)
			(layers "F.Cu" "F.Mask" "F.Paste")
			(net "GND")
		)
		(pad "DT77" smd circle
			(at 26.030682 17.676114 270)
			(size 0.4318 0.4318)
			(layers "F.Cu" "F.Mask" "F.Paste")
			(net "M_H_CPU0_SA_DQ<1>")
		)
		(pad "DT79" smd circle
			(at 27.658314 17.676114 270)
			(size 0.4318 0.4318)
			(layers "F.Cu" "F.Mask" "F.Paste")
			(net "PVCCFA_EHV_FIVRA_CPU0")
		)
		(pad "DT81" smd circle
			(at 29.2862 17.676114 270)
			(size 0.4318 0.4318)
			(layers "F.Cu" "F.Mask" "F.Paste")
			(net "Net_657")
		)
		(pad "DT83" smd circle
			(at 30.914086 17.676114 270)
			(size 0.4318 0.4318)
			(layers "F.Cu" "F.Mask" "F.Paste")
			(net "GND")
		)
		(pad "DT85" smd circle
			(at 32.541718 17.676114 270)
			(size 0.4318 0.4318)
			(layers "F.Cu" "F.Mask" "F.Paste")
			(net "PVCCFA_EHV_FIVRA_CPU0")
		)
		(pad "DT87" smd circle
			(at 34.169604 17.676114 270)
			(size 0.4318 0.4318)
			(layers "F.Cu" "F.Mask" "F.Paste")
			(net "P5E_CPU0_PE3_TX_DN<4>")
		)
		(pad "DT89" smd circle
			(at 35.797236 17.676114 270)
			(size 0.4318 0.4318)
			(layers "F.Cu" "F.Mask" "F.Paste")
			(net "PVCCFA_EHV_FIVRA_CPU0")
		)
		(pad "DT91" smd oval
			(at 37.425122 17.676114)
			(size 0.381 0.4826)
			(drill
				(offset 0 -0.0508)
			)
			(layers "F.Cu" "F.Mask" "F.Paste")
			(net "P5E_CPU0_PE3_RX_DP<5>")
		)
		(pad "DU1" smd oval
			(at -37.425122 18.036286 180)
			(size 0.381 0.4826)
			(drill
				(offset 0 -0.0508)
			)
			(layers "F.Cu" "F.Mask" "F.Paste")
			(net "UPI_CPU1_CPU0_P0P1_DN<5>")
		)
		(pad "DU3" smd circle
			(at -35.797236 18.036286 270)
			(size 0.4318 0.4318)
			(layers "F.Cu" "F.Mask" "F.Paste")
			(net "PVCCFA_EHV_FIVRA_CPU0")
		)
		(pad "DU5" smd circle
			(at -34.169604 18.036286 270)
			(size 0.4318 0.4318)
			(layers "F.Cu" "F.Mask" "F.Paste")
			(net "UPI_CPU0_CPU1_P1P0_DP<4>")
		)
		(pad "DU7" smd circle
			(at -32.541718 18.036286 270)
			(size 0.4318 0.4318)
			(layers "F.Cu" "F.Mask" "F.Paste")
			(net "PVCCFA_EHV_FIVRA_CPU0")
		)
		(pad "DU9" smd circle
			(at -30.914086 18.036286 270)
			(size 0.4318 0.4318)
			(layers "F.Cu" "F.Mask" "F.Paste")
			(net "P5E_CPU0_PE2_RX_DN<10>")
		)
		(pad "DU11" smd circle
			(at -29.2862 18.036286 270)
			(size 0.4318 0.4318)
			(layers "F.Cu" "F.Mask" "F.Paste")
			(net "PVCCFA_EHV_FIVRA_CPU0")
		)
		(pad "DU13" smd circle
			(at -27.658314 18.036286 270)
			(size 0.4318 0.4318)
			(layers "F.Cu" "F.Mask" "F.Paste")
			(net "P5E_CPU0_PE2_TX_DN<10>")
		)
		(pad "DU15" smd circle
			(at -26.030682 18.036286 270)
			(size 0.4318 0.4318)
			(layers "F.Cu" "F.Mask" "F.Paste")
			(net "PVCCFA_EHV_FIVRA_CPU0")
		)
		(pad "DU17" smd circle
			(at -24.402796 18.036286 270)
			(size 0.4318 0.4318)
			(layers "F.Cu" "F.Mask" "F.Paste")
			(net "M_F_CPU0_SB_DQ<29>")
		)
		(pad "DU19" smd circle
			(at -22.77491 18.036286 270)
			(size 0.4318 0.4318)
			(layers "F.Cu" "F.Mask" "F.Paste")
			(net "M_F_CPU0_SB_DQ<25>")
		)
		(pad "DU21" smd circle
			(at -21.147278 18.036286 270)
			(size 0.4318 0.4318)
			(layers "F.Cu" "F.Mask" "F.Paste")
			(net "GND")
		)
		(pad "DU23" smd circle
			(at -19.519392 18.036286 270)
			(size 0.4318 0.4318)
			(layers "F.Cu" "F.Mask" "F.Paste")
			(net "M_G_CPU0_SB_DQ<20>")
		)
		(pad "DU25" smd circle
			(at -17.89176 18.036286 270)
			(size 0.4318 0.4318)
			(layers "F.Cu" "F.Mask" "F.Paste")
			(net "M_G_CPU0_SB_DQ<17>")
		)
		(pad "DU27" smd circle
			(at -16.263874 18.036286 270)
			(size 0.4318 0.4318)
			(layers "F.Cu" "F.Mask" "F.Paste")
			(net "GND")
		)
		(pad "DU29" smd circle
			(at -14.635988 18.036286 270)
			(size 0.4318 0.4318)
			(layers "F.Cu" "F.Mask" "F.Paste")
			(net "M_F_CPU0_SB_DQ<4>")
		)
		(pad "DU31" smd circle
			(at -13.008356 18.036286 270)
			(size 0.4318 0.4318)
			(layers "F.Cu" "F.Mask" "F.Paste")
			(net "M_F_CPU0_SB_DQ<1>")
		)
		(pad "DU33" smd circle
			(at -11.380724 18.036286 270)
			(size 0.4318 0.4318)
			(layers "F.Cu" "F.Mask" "F.Paste")
			(net "GND")
		)
		(pad "DU35" smd circle
			(at -9.752838 18.036286 270)
			(size 0.4318 0.4318)
			(layers "F.Cu" "F.Mask" "F.Paste")
			(net "M_G_CPU0_SB_CB<0>")
		)
		(pad "DU37" smd circle
			(at -8.124952 18.036286 270)
			(size 0.4318 0.4318)
			(layers "F.Cu" "F.Mask" "F.Paste")
			(net "M_G_CPU0_SB_CB<5>")
		)
		(pad "DU39" smd circle
			(at -6.49732 18.036286 270)
			(size 0.4318 0.4318)
			(layers "F.Cu" "F.Mask" "F.Paste")
			(net "GND")
		)
		(pad "DU41" smd circle
			(at -4.869434 18.036286 270)
			(size 0.4318 0.4318)
			(layers "F.Cu" "F.Mask" "F.Paste")
			(net "M_G_CPU0_SB_CS_N<2>")
		)
		(pad "DU43" smd circle
			(at -3.241802 18.036286 270)
			(size 0.4318 0.4318)
			(layers "F.Cu" "F.Mask" "F.Paste")
			(net "M_G_CPU0_SB_CA<4>")
		)
		(pad "DU45" smd circle
			(at -1.613916 18.036286 270)
			(size 0.4318 0.4318)
			(layers "F.Cu" "F.Mask" "F.Paste")
			(net "GND")
		)
	)
)
